# T6G (Grand Teton) — schematic netlist excerpt (pin names and nets, part order shuffled) for the footprints in the layout excerpt that follows; sources: Cadence DE-HDL packaged netlist, KiCad conversion of 04192023_DAF0TMB3IC0_F0TG_MB_C_brd_V02_OCP.brd

R1492  Q_RES  10K 5% CHIP  pkg 0402LF  page 188 : A = P3V3_AUX ; B = PWRGD_P3V3_EN_N
R6014  Q_RES  0 5% CHIP  pkg 0402LF  page 150 : A = SGPIO_SCM_DI_<1> ; B = SGPIO_SCM_DI_R_<1>

(kicad_pcb
	(version 20260206)
	(generator "pcbnew")
	(generator_version "10.0")
	(general
		(thickness 1.6)
		(legacy_teardrops no)
	)
	(paper "A4")
	(title_block
		(title "04192023_DAF0TMB3IC0_F0TG_MB_C_brd_V02_OCP.brd")
		(comment 1 "Grand Teton / footprints 593-594 of 8354")
	)
	(layers
		(0 "F.Cu" signal "TOP")
		(4 "In1.Cu" signal "GND")
		(6 "In2.Cu" signal "IN1")
		(8 "In3.Cu" signal "GND1")
		(10 "In4.Cu" signal "IN2")
		(12 "In5.Cu" signal "GND2")
		(14 "In6.Cu" signal "IN3")
		(16 "In7.Cu" signal "GND3")
		(18 "In8.Cu" signal "VCC")
		(20 "In9.Cu" signal "VCC1")
		(22 "In10.Cu" signal "GND4")
		(24 "In11.Cu" signal "IN4")
		(26 "In12.Cu" signal "GND5")
		(28 "In13.Cu" signal "IN5")
		(30 "In14.Cu" signal "GND6")
		(32 "In15.Cu" signal "IN6")
		(34 "In16.Cu" signal "GND7")
		(2 "B.Cu" signal "BOTTOM")
		(9 "F.Adhes" user "F.Adhesive")
		(11 "B.Adhes" user "B.Adhesive")
		(13 "F.Paste" user "Package Geometry/Pastemask Top")
		(15 "B.Paste" user "Package Geometry/Pastemask Bottom")
		(5 "F.SilkS" user "Ref Des/Silkscreen Top")
		(7 "B.SilkS" user "Ref Des/Silkscreen Bottom")
		(1 "F.Mask" user "Board Geometry/Soldermask Top")
		(3 "B.Mask" user "Board Geometry/Soldermask Bottom")
		(17 "Dwgs.User" user "User.Drawings")
		(19 "Cmts.User" user "User.Comments")
		(21 "Eco1.User" user "User.Eco1")
		(23 "Eco2.User" user "User.Eco2")
		(25 "Edge.Cuts" user "Board Geometry/Outline")
		(27 "Margin" user)
		(31 "F.CrtYd" user "Package Geometry/Place Bound Top")
		(29 "B.CrtYd" user "Package Geometry/Place Bound Bottom")
		(35 "F.Fab" user "Ref Des/Assembly Top")
		(33 "B.Fab" user "Ref Des/Assembly Bottom")
	)
	(footprint ""
		(layer "F.Cu")
		(at 109.165136 -119.46001 90)
		(property "Reference" "R1492"
			(at 0 0 90)
			(layer "F.SilkS")
			(hide yes)
			(effects
				(font
					(size 1.27 1.27)
				)
			)
		)
		(property "Value" ""
			(at 0 0 90)
			(layer "F.Fab")
			(effects
				(font
					(size 1.27 1.27)
				)
			)
		)
		(duplicate_pad_numbers_are_jumpers no)
		(fp_line
			(start 0.7874 -0.4064)
			(end 0.7874 0.4064)
			(stroke
				(width 0.1524)
				(type default)
			)
			(layer "F.SilkS")
		)
		(fp_line
			(start -0.7874 -0.4064)
			(end 0.7874 -0.4064)
			(stroke
				(width 0.1524)
				(type default)
			)
			(layer "F.SilkS")
		)
		(fp_line
			(start 0.7874 0.4064)
			(end -0.7874 0.4064)
			(stroke
				(width 0.1524)
				(type default)
			)
			(layer "F.SilkS")
		)
		(fp_line
			(start -0.7874 0.4064)
			(end -0.7874 -0.4064)
			(stroke
				(width 0.1524)
				(type default)
			)
			(layer "F.SilkS")
		)
		(fp_line
			(start -0.12065 -0.305054)
			(end -0.12065 -0.2794)
			(stroke
				(width 0.1)
				(type default)
			)
			(layer "F.Fab")
		)
		(fp_line
			(start -0.67945 -0.305054)
			(end -0.12065 -0.305054)
			(stroke
				(width 0.1)
				(type default)
			)
			(layer "F.Fab")
		)
		(fp_line
			(start 0.67945 -0.3048)
			(end 0.67945 0.3048)
			(stroke
				(width 0.1)
				(type default)
			)
			(layer "F.Fab")
		)
		(fp_line
			(start 0.12065 -0.3048)
			(end 0.67945 -0.3048)
			(stroke
				(width 0.1)
				(type default)
			)
			(layer "F.Fab")
		)
		(fp_line
			(start 0.12065 -0.2794)
			(end 0.12065 -0.3048)
			(stroke
				(width 0.1)
				(type default)
			)
			(layer "F.Fab")
		)
		(fp_line
			(start -0.12065 -0.2794)
			(end 0.12065 -0.2794)
			(stroke
				(width 0.1)
				(type default)
			)
			(layer "F.Fab")
		)
		(fp_line
			(start 0.120396 0.2794)
			(end -0.12065 0.2794)
			(stroke
				(width 0.1)
				(type default)
			)
			(layer "F.Fab")
		)
		(fp_line
			(start -0.12065 0.2794)
			(end -0.12065 0.3048)
			(stroke
				(width 0.1)
				(type default)
			)
			(layer "F.Fab")
		)
		(fp_line
			(start 0.67945 0.3048)
			(end 0.120396 0.3048)
			(stroke
				(width 0.1)
				(type default)
			)
			(layer "F.Fab")
		)
		(fp_line
			(start 0.120396 0.3048)
			(end 0.120396 0.2794)
			(stroke
				(width 0.1)
				(type default)
			)
			(layer "F.Fab")
		)
		(fp_line
			(start -0.12065 0.3048)
			(end -0.67945 0.3048)
			(stroke
				(width 0.1)
				(type default)
			)
			(layer "F.Fab")
		)
		(fp_line
			(start -0.67945 0.3048)
			(end -0.67945 -0.305054)
			(stroke
				(width 0.1)
				(type default)
			)
			(layer "F.Fab")
		)
		(pad "1" smd circle
			(at -0.40005 0 90)
			(size 0 0)
			(layers "F.Cu" "F.Mask" "F.Paste")
			(net "P3V3_AUX")
		)
		(pad "2" smd circle
			(at 0.40005 0 90)
			(size 0 0)
			(layers "F.Cu" "F.Mask" "F.Paste")
			(net "PWRGD_P3V3_EN_N")
		)
	)
	(footprint ""
		(layer "F.Cu")
		(at 152.97912 -23.284942 -90)
		(property "Reference" "R6014"
			(at 0 0 270)
			(layer "F.SilkS")
			(hide yes)
			(effects
				(font
					(size 1.27 1.27)
				)
			)
		)
		(property "Value" ""
			(at 0 0 270)
			(layer "F.Fab")
			(effects
				(font
					(size 1.27 1.27)
				)
			)
		)
		(duplicate_pad_numbers_are_jumpers no)
		(fp_line
			(start -0.7874 0.4064)
			(end -0.7874 -0.4064)
			(stroke
				(width 0.1524)
				(type default)
			)
			(layer "F.SilkS")
		)
		(fp_line
			(start 0.7874 0.4064)
			(end -0.7874 0.4064)
			(stroke
				(width 0.1524)
				(type default)
			)
			(layer "F.SilkS")
		)
		(fp_line
			(start -0.7874 -0.4064)
			(end 0.7874 -0.4064)
			(stroke
				(width 0.1524)
				(type default)
			)
			(layer "F.SilkS")
		)
		(fp_line
			(start 0.7874 -0.4064)
			(end 0.7874 0.4064)
			(stroke
				(width 0.1524)
				(type default)
			)
			(layer "F.SilkS")
		)
		(fp_line
			(start -0.67945 0.3048)
			(end -0.67945 -0.305054)
			(stroke
				(width 0.1)
				(type default)
			)
			(layer "F.Fab")
		)
		(fp_line
			(start -0.12065 0.3048)
			(end -0.67945 0.3048)
			(stroke
				(width 0.1)
				(type default)
			)
			(layer "F.Fab")
		)
		(fp_line
			(start 0.120396 0.3048)
			(end 0.120396 0.2794)
			(stroke
				(width 0.1)
				(type default)
			)
			(layer "F.Fab")
		)
		(fp_line
			(start 0.67945 0.3048)
			(end 0.120396 0.3048)
			(stroke
				(width 0.1)
				(type default)
			)
			(layer "F.Fab")
		)
		(fp_line
			(start -0.12065 0.2794)
			(end -0.12065 0.3048)
			(stroke
				(width 0.1)
				(type default)
			)
			(layer "F.Fab")
		)
		(fp_line
			(start 0.120396 0.2794)
			(end -0.12065 0.2794)
			(stroke
				(width 0.1)
				(type default)
			)
			(layer "F.Fab")
		)
		(fp_line
			(start -0.12065 -0.2794)
			(end 0.12065 -0.2794)
			(stroke
				(width 0.1)
				(type default)
			)
			(layer "F.Fab")
		)
		(fp_line
			(start 0.12065 -0.2794)
			(end 0.12065 -0.3048)
			(stroke
				(width 0.1)
				(type default)
			)
			(layer "F.Fab")
		)
		(fp_line
			(start 0.12065 -0.3048)
			(end 0.67945 -0.3048)
			(stroke
				(width 0.1)
				(type default)
			)
			(layer "F.Fab")
		)
		(fp_line
			(start 0.67945 -0.3048)
			(end 0.67945 0.3048)
			(stroke
				(width 0.1)
				(type default)
			)
			(layer "F.Fab")
		)
		(fp_line
			(start -0.67945 -0.305054)
			(end -0.12065 -0.305054)
			(stroke
				(width 0.1)
				(type default)
			)
			(layer "F.Fab")
		)
		(fp_line
			(start -0.12065 -0.305054)
			(end -0.12065 -0.2794)
			(stroke
				(width 0.1)
				(type default)
			)
			(layer "F.Fab")
		)
		(pad "1" smd circle
			(at -0.40005 0 270)
			(size 0 0)
			(layers "F.Cu" "F.Mask" "F.Paste")
			(net "SGPIO_SCM_DI_<1>")
		)
		(pad "2" smd circle
			(at 0.40005 0 270)
			(size 0 0)
			(layers "F.Cu" "F.Mask" "F.Paste")
			(net "SGPIO_SCM_DI_R_<1>")
		)
	)
)
